(kicad_pcb
	(version 20260206)
	(generator "pcbnew")
	(generator_version "10.0")
	(general
		(thickness 1.21888)
		(legacy_teardrops no)
	)
	(paper "A4")
	(title_block
		(title "timecard-v9 — TimeCard-DC-V9_EXP.PcbDoc")
		(comment 1 "Time Appliance Project (Time Card) / footprints 165-177 of 402")
	)
	(layers
		(0 "F.Cu" signal "TOP")
		(4 "In1.Cu" signal "SGND")
		(6 "In2.Cu" signal "IN1")
		(8 "In3.Cu" signal "IN2")
		(10 "In4.Cu" signal "SGND1")
		(2 "B.Cu" signal "BOTTOM")
		(9 "F.Adhes" user "F.Adhesive")
		(11 "B.Adhes" user "B.Adhesive")
		(13 "F.Paste" user "Top Paste")
		(15 "B.Paste" user "Bottom Paste")
		(5 "F.SilkS" user "Top Overlay")
		(7 "B.SilkS" user "Bottom Overlay")
		(1 "F.Mask" user "Top Solder")
		(3 "B.Mask" user "Bottom Solder")
		(17 "Dwgs.User" user "User.Drawings")
		(19 "Cmts.User" user "User.Comments")
		(21 "Eco1.User" user "User.Eco1")
		(23 "Eco2.User" user "User.Eco2")
		(25 "Edge.Cuts" user)
		(27 "Margin" user)
		(31 "F.CrtYd" user "Top Courtyard")
		(29 "B.CrtYd" user "Bottom Courtyard")
		(35 "F.Fab" user "Top Component Center")
		(33 "B.Fab" user "Bottom Component Center")
	)
	(footprint "Vault:RESC1005X40X25LL05T10"
		(layer "F.Cu")
		(at 109.4216 51.1162 90)
		(property "Reference" "R144"
			(at -0.4968 8.326921 90)
			(unlocked yes)
			(layer "F.SilkS")
			(effects
				(font
					(size 0.762 0.762)
					(thickness 0.2032)
				)
			)
		)
		(property "Value" "49.9_1%_0402"
			(at -2.579871 8.798265 0)
			(unlocked yes)
			(layer "F.SilkS")
			(hide yes)
			(effects
				(font
					(size 0.762 0.762)
					(thickness 0.2032)
				)
			)
		)
		(sheetname "11-M2_RCB_MUX")
		(sheetfile "11-M2_RCB_MUX.kicad_sch")
		(duplicate_pad_numbers_are_jumpers no)
		(pad "1" smd rect
			(at -0.375 0 180)
			(size 0.45 0.5)
			(layers "F.Cu" "F.Mask" "F.Paste")
			(net "NetR144_1")
		)
		(pad "2" smd rect
			(at 0.375 0 180)
			(size 0.45 0.5)
			(layers "F.Cu" "F.Mask" "F.Paste")
			(net "GPS1_TX")
		)
	)
	(footprint "Vault:TECO-1909763-1_V"
		(layer "F.Cu")
		(at 77.19563 135.6162 -90)
		(property "Reference" "J4"
			(at -2.873079 -1.254575 0)
			(unlocked yes)
			(layer "F.SilkS")
			(effects
				(font
					(size 0.762 0.762)
					(thickness 0.2286)
				)
			)
		)
		(property "Value" "1909763-1"
			(at 4.582685 3.722871 270)
			(unlocked yes)
			(layer "F.SilkS")
			(hide yes)
			(effects
				(font
					(size 0.762 0.762)
					(thickness 0.2286)
				)
			)
		)
		(sheetname "01-USER_IO")
		(sheetfile "01-USER_IO.kicad_sch")
		(duplicate_pad_numbers_are_jumpers no)
		(fp_line
			(start 0.55 -1.3)
			(end -0.55 -1.3)
			(stroke
				(width 0.2)
				(type solid)
			)
			(layer "F.SilkS")
		)
		(fp_circle
			(center -1.778 1.65)
			(end -1.903 1.65)
			(stroke
				(width 0.25)
				(type solid)
			)
			(fill no)
			(layer "F.SilkS")
		)
		(pad "1" smd rect
			(at -1.475 0 270)
			(size 1.05 2.2)
			(layers "F.Cu" "F.Mask" "F.Paste")
			(net "GND")
		)
		(pad "2" smd rect
			(at 0 1.525 270)
			(size 1 1.05)
			(layers "F.Cu" "F.Mask" "F.Paste")
			(net "NetAN4_1")
		)
		(pad "3" smd rect
			(at 1.475 0 270)
			(size 1.05 2.2)
			(layers "F.Cu" "F.Mask" "F.Paste")
			(net "GND")
		)
	)
	(footprint "Vault:RESC1005X40X25LL05T10"
		(layer "F.Cu")
		(at 142.8216 102.2162 -90)
		(property "Reference" "R96"
			(at -2.3286 0.073069 90)
			(unlocked yes)
			(layer "F.SilkS")
			(effects
				(font
					(size 0.762 0.762)
					(thickness 0.2286)
				)
			)
		)
		(property "Value" "49.9_1%_0402"
			(at -2.579871 8.823675 180)
			(unlocked yes)
			(layer "F.SilkS")
			(hide yes)
			(effects
				(font
					(size 0.762 0.762)
					(thickness 0.2286)
				)
			)
		)
		(sheetname "09-USBUart_PPSMUX_UARTMUX")
		(sheetfile "09-USBUart_PPSMUX_UARTMUX.kicad_sch")
		(duplicate_pad_numbers_are_jumpers no)
		(pad "1" smd rect
			(at -0.375 0)
			(size 0.45 0.5)
			(layers "F.Cu" "F.Mask" "F.Paste")
			(net "MAC_PPS_OUT")
		)
		(pad "2" smd rect
			(at 0.375 0)
			(size 0.45 0.5)
			(layers "F.Cu" "F.Mask" "F.Paste")
			(net "NetR96_2")
		)
	)
	(footprint "Vault:RESC1005X40X25NL05T05"
		(layer "F.Cu")
		(at 223.8216 91.8162 180)
		(property "Reference" "R179"
			(at 2.3968 0.173069 0)
			(unlocked yes)
			(layer "F.SilkS")
			(effects
				(font
					(size 0.762 0.762)
					(thickness 0.2032)
				)
			)
		)
		(property "Value" "200_1%_0402"
			(at -2.732271 8.112675 90)
			(unlocked yes)
			(layer "F.SilkS")
			(hide yes)
			(effects
				(font
					(size 0.762 0.762)
					(thickness 0.2032)
				)
			)
		)
		(sheetname "08-DIPSwitches_I2C")
		(sheetfile "08-DIPSwitches_I2C.kicad_sch")
		(duplicate_pad_numbers_are_jumpers no)
		(pad "1" smd rect
			(at -0.45 0 270)
			(size 0.55 0.55)
			(layers "F.Cu" "F.Mask" "F.Paste")
			(net "NetD19_1")
		)
		(pad "2" smd rect
			(at 0.45 0 270)
			(size 0.55 0.55)
			(layers "F.Cu" "F.Mask" "F.Paste")
			(net "DIP_SW_GPS1_SEL")
		)
	)
	(footprint "Vault:FP-C1005-050-0_05-IPC_A"
		(layer "F.Cu")
		(at 162.25767 83.8662 180)
		(property "Reference" "C81"
			(at 2.107465 -0.076931 0)
			(unlocked yes)
			(layer "F.SilkS")
			(effects
				(font
					(size 0.762 0.762)
					(thickness 0.2286)
				)
			)
		)
		(property "Value" "2.2uF_16V_0402"
			(at 9.509015 2.440151 180)
			(unlocked yes)
			(layer "F.SilkS")
			(hide yes)
			(effects
				(font
					(size 0.762 0.762)
					(thickness 0.2286)
				)
			)
		)
		(sheetname "03-POWER")
		(sheetfile "03-POWER.kicad_sch")
		(duplicate_pad_numbers_are_jumpers no)
		(fp_line
			(start 0.83623 0.73624)
			(end -0.83624 0.73624)
			(stroke
				(width 0.2)
				(type solid)
			)
			(layer "F.SilkS")
		)
		(fp_line
			(start 0.83623 -0.73624)
			(end -0.83624 -0.73624)
			(stroke
				(width 0.2)
				(type solid)
			)
			(layer "F.SilkS")
		)
		(fp_line
			(start 1.03623 0.53624)
			(end -1.03624 0.53624)
			(stroke
				(width 0.2)
				(type solid)
			)
			(layer "F.CrtYd")
		)
		(fp_line
			(start 1.03623 -0.53624)
			(end 1.03623 0.53624)
			(stroke
				(width 0.2)
				(type solid)
			)
			(layer "F.CrtYd")
		)
		(fp_line
			(start 1.03623 -0.53624)
			(end -1.03624 -0.53624)
			(stroke
				(width 0.2)
				(type solid)
			)
			(layer "F.CrtYd")
		)
		(fp_line
			(start -1.03624 -0.53624)
			(end -1.03624 0.53624)
			(stroke
				(width 0.2)
				(type solid)
			)
			(layer "F.CrtYd")
		)
		(fp_line
			(start 1.03623 0.53624)
			(end -1.03624 0.53624)
			(stroke
				(width 0.2)
				(type solid)
			)
			(layer "F.Fab")
		)
		(fp_line
			(start 1.03623 -0.53624)
			(end 1.03623 0.53624)
			(stroke
				(width 0.2)
				(type solid)
			)
			(layer "F.Fab")
		)
		(fp_line
			(start 1.03623 -0.53624)
			(end -1.03624 -0.53624)
			(stroke
				(width 0.2)
				(type solid)
			)
			(layer "F.Fab")
		)
		(fp_line
			(start 0.5 0)
			(end -0.5 0)
			(stroke
				(width 0.1)
				(type solid)
			)
			(layer "F.Fab")
		)
		(fp_line
			(start 0 -0.5)
			(end 0 0.5)
			(stroke
				(width 0.1)
				(type solid)
			)
			(layer "F.Fab")
		)
		(fp_line
			(start -1.03624 -0.53624)
			(end -1.03624 0.53624)
			(stroke
				(width 0.2)
				(type solid)
			)
			(layer "F.Fab")
		)
		(fp_text user "${REFERENCE}"
			(at -0.00001 0.09601 180)
			(unlocked yes)
			(layer "F.Fab")
			(effects
				(font
					(face "Arial")
					(size 0.63 0.63)
					(thickness 0.1)
				)
				(justify left bottom)
			)
		)
		(pad "1" smd rect
			(at -0.46658 0 180)
			(size 0.73933 0.67248)
			(layers "F.Cu" "F.Mask" "F.Paste")
			(net "+3.3V")
			(solder_mask_margin 0)
			(solder_paste_margin 0)
		)
		(pad "2" smd rect
			(at 0.46657 0 180)
			(size 0.73933 0.67248)
			(layers "F.Cu" "F.Mask" "F.Paste")
			(net "GND")
			(solder_mask_margin 0)
			(solder_paste_margin 0)
		)
	)
	(footprint "SamacSys:155124M173200"
		(layer "F.Cu")
		(at 67.4466 82.6662 90)
		(property "Reference" "D14"
			(at -4.7 -0.231655 90)
			(unlocked yes)
			(layer "F.SilkS")
			(effects
				(font
					(size 0.762 0.762)
					(thickness 0.2286)
				)
				(justify left bottom)
			)
		)
		(property "Value" "155124M173200"
			(at -4.043045 -0.5715 0)
			(unlocked yes)
			(layer "F.SilkS")
			(hide yes)
			(effects
				(font
					(size 0.762 0.762)
					(thickness 0.2286)
				)
				(justify left bottom)
			)
		)
		(sheetname "02-USER_IO_STATUS")
		(sheetfile "02-USER_IO_STATUS.kicad_sch")
		(duplicate_pad_numbers_are_jumpers no)
		(fp_line
			(start -0.8 0.5)
			(end 0.8 0.5)
			(stroke
				(width 0.1)
				(type solid)
			)
			(layer "F.SilkS")
		)
		(fp_arc
			(start -2 -0.1008)
			(mid -1.9492 -0.05)
			(end -2 0.0008)
			(stroke
				(width 0.381)
				(type solid)
			)
			(layer "F.SilkS")
		)
		(fp_arc
			(start -2 0.0008)
			(mid -2.0508 -0.05)
			(end -2 -0.1008)
			(stroke
				(width 0.381)
				(type solid)
			)
			(layer "F.SilkS")
		)
		(pad "1" smd rect
			(at -1.4 0 180)
			(size 0.9 0.6)
			(layers "F.Cu" "F.Mask" "F.Paste")
			(net "+3.3V")
		)
		(pad "2" smd rect
			(at -0.45 -0.325 90)
			(size 0.6 0.55)
			(layers "F.Cu" "F.Mask" "F.Paste")
			(net "NetD14_2")
		)
		(pad "3" smd rect
			(at 0.45 -0.325 90)
			(size 0.6 0.55)
			(layers "F.Cu" "F.Mask" "F.Paste")
			(net "NetD14_3")
		)
		(pad "4" smd rect
			(at 1.4 0 180)
			(size 0.9 0.6)
			(layers "F.Cu" "F.Mask" "F.Paste")
			(net "NetD14_4")
		)
	)
	(footprint "SA53:SolderSocket"
		(locked yes)
		(layer "F.Cu")
		(at 86.9216 117.0162 90)
		(property "Reference" "SKT6"
			(at -0.126921 -6.9714 0)
			(unlocked yes)
			(layer "F.SilkS")
			(effects
				(font
					(size 0.762 0.762)
					(thickness 0.2286)
				)
			)
		)
		(property "Value" "0332-0-43-80-18-27-10-0"
			(at -2.910071 16.1362 0)
			(unlocked yes)
			(layer "F.SilkS")
			(hide yes)
			(effects
				(font
					(size 0.762 0.762)
					(thickness 0.2286)
				)
			)
		)
		(sheetname "06-MAC")
		(sheetfile "06-MAC.kicad_sch")
		(duplicate_pad_numbers_are_jumpers no)
		(pad "1" thru_hole circle
			(at 0 0 90)
			(size 2.54 2.54)
			(drill 2.0066)
			(layers "*.Cu" "*.Mask")
			(remove_unused_layers no)
			(net "GND")
			(thermal_bridge_angle 90)
		)
	)
	(footprint "Vault:FP-T495D107K016ATE125-MFG"
		(layer "F.Cu")
		(at 96.4216 74.7162 180)
		(property "Reference" "C14"
			(at 4.206655 0.7 90)
			(unlocked yes)
			(layer "F.SilkS")
			(effects
				(font
					(size 0.762 0.762)
					(thickness 0.2286)
				)
				(justify left bottom)
			)
		)
		(property "Value" "100uF_16V_2917"
			(at -5.7281 -15.597845 0)
			(unlocked yes)
			(layer "F.SilkS")
			(hide yes)
			(effects
				(font
					(size 0.762 0.762)
					(thickness 0.2286)
				)
				(justify left bottom)
			)
		)
		(sheetname "03-POWER")
		(sheetfile "03-POWER.kicad_sch")
		(duplicate_pad_numbers_are_jumpers no)
		(fp_line
			(start 5 0)
			(end 4.4 0)
			(stroke
				(width 0.2)
				(type solid)
			)
			(layer "F.SilkS")
		)
		(fp_line
			(start 4.7 -0.3)
			(end 4.7 0.3)
			(stroke
				(width 0.2)
				(type solid)
			)
			(layer "F.SilkS")
		)
		(fp_line
			(start 3.8 2.3)
			(end -3.8 2.3)
			(stroke
				(width 0.2)
				(type solid)
			)
			(layer "F.SilkS")
		)
		(fp_line
			(start 3.8 1.54)
			(end 3.8 2.3)
			(stroke
				(width 0.2)
				(type solid)
			)
			(layer "F.SilkS")
		)
		(fp_line
			(start 3.8 -2.3)
			(end 3.8 -1.54)
			(stroke
				(width 0.2)
				(type solid)
			)
			(layer "F.SilkS")
		)
		(fp_line
			(start 3.8 -2.3)
			(end -3.8 -2.3)
			(stroke
				(width 0.2)
				(type solid)
			)
			(layer "F.SilkS")
		)
		(fp_line
			(start -3.8 1.54)
			(end -3.8 2.3)
			(stroke
				(width 0.2)
				(type solid)
			)
			(layer "F.SilkS")
		)
		(fp_line
			(start -3.8 -2.3)
			(end -3.8 -1.54)
			(stroke
				(width 0.2)
				(type solid)
			)
			(layer "F.SilkS")
		)
		(fp_line
			(start 4.105 2.4)
			(end -4.105 2.4)
			(stroke
				(width 0.2)
				(type solid)
			)
			(layer "F.CrtYd")
		)
		(fp_line
			(start 4.105 -2.4)
			(end 4.105 2.4)
			(stroke
				(width 0.2)
				(type solid)
			)
			(layer "F.CrtYd")
		)
		(fp_line
			(start 4.105 -2.4)
			(end -4.105 -2.4)
			(stroke
				(width 0.2)
				(type solid)
			)
			(layer "F.CrtYd")
		)
		(fp_line
			(start -4.105 -2.4)
			(end -4.105 2.4)
			(stroke
				(width 0.2)
				(type solid)
			)
			(layer "F.CrtYd")
		)
		(fp_line
			(start 4.105 2.4)
			(end -4.105 2.4)
			(stroke
				(width 0.2)
				(type solid)
			)
			(layer "F.Fab")
		)
		(fp_line
			(start 4.105 -2.4)
			(end 4.105 2.4)
			(stroke
				(width 0.2)
				(type solid)
			)
			(layer "F.Fab")
		)
		(fp_line
			(start 4.105 -2.4)
			(end -4.105 -2.4)
			(stroke
				(width 0.2)
				(type solid)
			)
			(layer "F.Fab")
		)
		(fp_line
			(start 0.5 0)
			(end -0.5 0)
			(stroke
				(width 0.1)
				(type solid)
			)
			(layer "F.Fab")
		)
		(fp_line
			(start 0 -0.5)
			(end 0 0.5)
			(stroke
				(width 0.1)
				(type solid)
			)
			(layer "F.Fab")
		)
		(fp_line
			(start -4.105 -2.4)
			(end -4.105 2.4)
			(stroke
				(width 0.2)
				(type solid)
			)
			(layer "F.Fab")
		)
		(fp_text user "${REFERENCE}"
			(at 0 0.28425 180)
			(unlocked yes)
			(layer "F.Fab")
			(effects
				(font
					(face "Arial")
					(size 0.63 0.63)
					(thickness 0.1)
				)
				(justify left bottom)
			)
		)
		(pad "1" smd rect
			(at -3.01 0 180)
			(size 1.99 2.33)
			(layers "F.Cu" "F.Mask" "F.Paste")
			(net "GND")
			(solder_mask_margin 0)
			(solder_paste_margin 0)
		)
		(pad "2" smd rect
			(at 3.01 0 180)
			(size 1.99 2.33)
			(layers "F.Cu" "F.Mask" "F.Paste")
			(net "+5.0V")
			(solder_mask_margin 0)
			(solder_paste_margin 0)
		)
	)
	(footprint "Vault:RESC1005X40X25NL05T05"
		(layer "F.Cu")
		(at 112.7216 52.2162 90)
		(property "Reference" "R161"
			(at -0.0968 7.726921 90)
			(unlocked yes)
			(layer "F.SilkS")
			(effects
				(font
					(size 0.762 0.762)
					(thickness 0.2032)
				)
			)
		)
		(property "Value" "DNI_27_1%_0402"
			(at -2.732271 10.270975 0)
			(unlocked yes)
			(layer "F.SilkS")
			(hide yes)
			(effects
				(font
					(size 0.762 0.762)
					(thickness 0.2032)
				)
			)
		)
		(sheetname "11-M2_RCB_MUX")
		(sheetfile "11-M2_RCB_MUX.kicad_sch")
		(duplicate_pad_numbers_are_jumpers no)
		(pad "1" smd rect
			(at -0.45 0 180)
			(size 0.55 0.55)
			(layers "F.Cu" "F.Mask" "F.Paste")
			(net "RCB_GPS1_TP2")
		)
		(pad "2" smd rect
			(at 0.45 0 180)
			(size 0.55 0.55)
			(layers "F.Cu" "F.Mask" "F.Paste")
			(net "GPS1_TP2")
		)
	)
	(footprint "Resistors:RESC2012X50N"
		(layer "F.Cu")
		(at 205.5416 145.61546)
		(property "Reference" "R21"
			(at -1.25 -1.406655 0)
			(unlocked yes)
			(layer "F.SilkS")
			(effects
				(font
					(size 0.762 0.762)
					(thickness 0.2286)
				)
				(justify left bottom)
			)
		)
		(property "Value" "CRCW080533R0FKEA"
			(at 7.20584 2.241585 0)
			(unlocked yes)
			(layer "F.SilkS")
			(hide yes)
			(effects
				(font
					(size 0.762 0.762)
					(thickness 0.2286)
				)
				(justify left bottom)
			)
		)
		(sheetname "04-PCIe_JTAG")
		(sheetfile "04-PCIe_JTAG.kicad_sch")
		(duplicate_pad_numbers_are_jumpers no)
		(fp_line
			(start 0 0.762)
			(end 0 -0.762)
			(stroke
				(width 0.1524)
				(type solid)
			)
			(layer "F.SilkS")
		)
		(pad "1" smd rect
			(at -1 0 90)
			(size 1.45 0.95)
			(layers "F.Cu" "F.Mask" "F.Paste")
			(net "FPGA_TDI")
		)
		(pad "2" smd rect
			(at 1 0 90)
			(size 1.45 0.95)
			(layers "F.Cu" "F.Mask" "F.Paste")
			(net "NetP4_9")
		)
	)
	(footprint "Vault:RESC3116X65X50ML20T20"
		(layer "F.Cu")
		(at 224.3216 63.8162 -90)
		(property "Reference" "R44"
			(at 0.3286 -1.573069 270)
			(unlocked yes)
			(layer "F.SilkS")
			(effects
				(font
					(size 0.762 0.762)
					(thickness 0.2286)
				)
			)
		)
		(property "Value" "DNI_0_5%_1206"
			(at 7.27402 3.291071 270)
			(unlocked yes)
			(layer "F.SilkS")
			(hide yes)
			(effects
				(font
					(size 0.762 0.762)
					(thickness 0.2286)
				)
			)
		)
		(sheetname "03-POWER")
		(sheetfile "03-POWER.kicad_sch")
		(duplicate_pad_numbers_are_jumpers no)
		(fp_line
			(start 0.35 0.85)
			(end -0.35 0.85)
			(stroke
				(width 0.2)
				(type solid)
			)
			(layer "F.SilkS")
		)
		(fp_line
			(start 0.35 -0.85)
			(end -0.35 -0.85)
			(stroke
				(width 0.2)
				(type solid)
			)
			(layer "F.SilkS")
		)
		(pad "1" smd rect
			(at -1.475 0)
			(size 1.9 1.45)
			(layers "F.Cu" "F.Mask" "F.Paste")
			(net "+12V_PCIE")
		)
		(pad "2" smd rect
			(at 1.475 0)
			(size 1.9 1.45)
			(layers "F.Cu" "F.Mask" "F.Paste")
			(net "+12V_SENS")
		)
	)
	(footprint "SA53:SolderSocket"
		(locked yes)
		(layer "F.Cu")
		(at 127.5216 96.7162 90)
		(property "Reference" "SKT7"
			(at -2.726921 7.1286 0)
			(unlocked yes)
			(layer "F.SilkS")
			(effects
				(font
					(size 0.762 0.762)
					(thickness 0.2286)
				)
			)
		)
		(property "Value" "0332-0-43-80-18-27-10-0"
			(at -2.910071 16.1362 0)
			(unlocked yes)
			(layer "F.SilkS")
			(hide yes)
			(effects
				(font
					(size 0.762 0.762)
					(thickness 0.2286)
				)
			)
		)
		(sheetname "06-MAC")
		(sheetfile "06-MAC.kicad_sch")
		(duplicate_pad_numbers_are_jumpers no)
		(pad "1" thru_hole circle
			(at 0 0 90)
			(size 2.54 2.54)
			(drill 2.0066)
			(layers "*.Cu" "*.Mask")
			(remove_unused_layers no)
			(net "MAC_VCC")
			(thermal_bridge_angle 90)
		)
	)
	(footprint "Vault:RESC1005X40X25LL05T05"
		(layer "F.Cu")
		(at 118.58072 88.8662)
		(property "Reference" "R73"
			(at -0.13052 1.076921 0)
			(unlocked yes)
			(layer "F.SilkS")
			(effects
				(font
					(size 0.762 0.762)
					(thickness 0.2286)
				)
			)
		)
		(property "Value" "DNI_0_1%_0402"
			(at -2.579871 8.56975 270)
			(unlocked yes)
			(layer "F.SilkS")
			(hide yes)
			(effects
				(font
					(size 0.762 0.762)
					(thickness 0.2286)
				)
			)
		)
		(sheetname "05-GPS_IMU_SENSORS")
		(sheetfile "05-GPS_IMU_SENSORS.kicad_sch")
		(duplicate_pad_numbers_are_jumpers no)
		(pad "1" smd rect
			(at -0.4 0 90)
			(size 0.45 0.45)
			(layers "F.Cu" "F.Mask" "F.Paste")
			(net "BNO_XOUT32")
		)
		(pad "2" smd rect
			(at 0.40001 0 90)
			(size 0.45 0.45)
			(layers "F.Cu" "F.Mask" "F.Paste")
			(net "FPGA_BNO_XOUT32")
		)
	)
)
